# S9S_MB_2U (Grand Teton) — schematic netlist excerpt (pin names and nets, part order shuffled) for the footprints in the layout excerpt that follows; sources: Cadence DE-HDL packaged netlist, KiCad conversion of 03242023_DA0F0TMBIJ0_F0T_Motherboard_J_brd_V01_OCP.brd

R1221  Q_RES  1K 1% CHIP  pkg 0402LF  page 200 : A = FM_PCH_MCRO_LDO ; B = GND
R4294  Q_RES  100 1% CHIP  pkg 0402LF  page 122 : A = H_CPU1_MEMHOT_IN_LVC1_R1_N ; B = H_CPU1_MEMHOT_IN_LVC1_N

(kicad_pcb
	(version 20260206)
	(generator "pcbnew")
	(generator_version "10.0")
	(general
		(thickness 1.6)
		(legacy_teardrops no)
	)
	(paper "A4")
	(title_block
		(title "03242023_DA0F0TMBIJ0_F0T_Motherboard_J_brd_V01_OCP.brd")
		(comment 1 "Grand Teton / footprints 1868-1869 of 6105")
	)
	(layers
		(0 "F.Cu" signal "TOP")
		(4 "In1.Cu" signal "GND")
		(6 "In2.Cu" signal "IN1")
		(8 "In3.Cu" signal "GND1")
		(10 "In4.Cu" signal "IN2")
		(12 "In5.Cu" signal "GND2")
		(14 "In6.Cu" signal "IN3")
		(16 "In7.Cu" signal "GND3")
		(18 "In8.Cu" signal "VCC")
		(20 "In9.Cu" signal "VCC1")
		(22 "In10.Cu" signal "GND4")
		(24 "In11.Cu" signal "IN4")
		(26 "In12.Cu" signal "GND5")
		(28 "In13.Cu" signal "IN5")
		(30 "In14.Cu" signal "GND6")
		(32 "In15.Cu" signal "IN6")
		(34 "In16.Cu" signal "GND7")
		(2 "B.Cu" signal "BOTTOM")
		(9 "F.Adhes" user "F.Adhesive")
		(11 "B.Adhes" user "B.Adhesive")
		(13 "F.Paste" user "Package Geometry/Pastemask Top")
		(15 "B.Paste" user "Package Geometry/Pastemask Bottom")
		(5 "F.SilkS" user "Ref Des/Silkscreen Top")
		(7 "B.SilkS" user "Ref Des/Silkscreen Bottom")
		(1 "F.Mask" user "Board Geometry/Soldermask Top")
		(3 "B.Mask" user "Board Geometry/Soldermask Bottom")
		(17 "Dwgs.User" user "User.Drawings")
		(19 "Cmts.User" user "User.Comments")
		(21 "Eco1.User" user "User.Eco1")
		(23 "Eco2.User" user "User.Eco2")
		(25 "Edge.Cuts" user "Board Geometry/Outline")
		(27 "Margin" user)
		(31 "F.CrtYd" user "Package Geometry/Place Bound Top")
		(29 "B.CrtYd" user "Package Geometry/Place Bound Bottom")
		(35 "F.Fab" user "Ref Des/Assembly Top")
		(33 "B.Fab" user "Ref Des/Assembly Bottom")
	)
	(footprint ""
		(layer "F.Cu")
		(at 201.02068 -99.939348)
		(property "Reference" "R4294"
			(at 0 0 0)
			(layer "F.SilkS")
			(hide yes)
			(effects
				(font
					(size 1.27 1.27)
				)
			)
		)
		(property "Value" ""
			(at 0 0 0)
			(layer "F.Fab")
			(effects
				(font
					(size 1.27 1.27)
				)
			)
		)
		(duplicate_pad_numbers_are_jumpers no)
		(fp_line
			(start -0.7874 -0.4064)
			(end 0.7874 -0.4064)
			(stroke
				(width 0.1524)
				(type default)
			)
			(layer "F.SilkS")
		)
		(fp_line
			(start -0.7874 0.4064)
			(end -0.7874 -0.4064)
			(stroke
				(width 0.1524)
				(type default)
			)
			(layer "F.SilkS")
		)
		(fp_line
			(start 0.7874 -0.4064)
			(end 0.7874 0.4064)
			(stroke
				(width 0.1524)
				(type default)
			)
			(layer "F.SilkS")
		)
		(fp_line
			(start 0.7874 0.4064)
			(end -0.7874 0.4064)
			(stroke
				(width 0.1524)
				(type default)
			)
			(layer "F.SilkS")
		)
		(fp_line
			(start -0.67945 -0.305054)
			(end -0.12065 -0.305054)
			(stroke
				(width 0.1)
				(type default)
			)
			(layer "F.Fab")
		)
		(fp_line
			(start -0.67945 0.3048)
			(end -0.67945 -0.305054)
			(stroke
				(width 0.1)
				(type default)
			)
			(layer "F.Fab")
		)
		(fp_line
			(start -0.12065 -0.305054)
			(end -0.12065 -0.2794)
			(stroke
				(width 0.1)
				(type default)
			)
			(layer "F.Fab")
		)
		(fp_line
			(start -0.12065 -0.2794)
			(end 0.12065 -0.2794)
			(stroke
				(width 0.1)
				(type default)
			)
			(layer "F.Fab")
		)
		(fp_line
			(start -0.12065 0.2794)
			(end -0.12065 0.3048)
			(stroke
				(width 0.1)
				(type default)
			)
			(layer "F.Fab")
		)
		(fp_line
			(start -0.12065 0.3048)
			(end -0.67945 0.3048)
			(stroke
				(width 0.1)
				(type default)
			)
			(layer "F.Fab")
		)
		(fp_line
			(start 0.120396 0.2794)
			(end -0.12065 0.2794)
			(stroke
				(width 0.1)
				(type default)
			)
			(layer "F.Fab")
		)
		(fp_line
			(start 0.120396 0.3048)
			(end 0.120396 0.2794)
			(stroke
				(width 0.1)
				(type default)
			)
			(layer "F.Fab")
		)
		(fp_line
			(start 0.12065 -0.3048)
			(end 0.67945 -0.3048)
			(stroke
				(width 0.1)
				(type default)
			)
			(layer "F.Fab")
		)
		(fp_line
			(start 0.12065 -0.2794)
			(end 0.12065 -0.3048)
			(stroke
				(width 0.1)
				(type default)
			)
			(layer "F.Fab")
		)
		(fp_line
			(start 0.67945 -0.3048)
			(end 0.67945 0.3048)
			(stroke
				(width 0.1)
				(type default)
			)
			(layer "F.Fab")
		)
		(fp_line
			(start 0.67945 0.3048)
			(end 0.120396 0.3048)
			(stroke
				(width 0.1)
				(type default)
			)
			(layer "F.Fab")
		)
		(pad "1" smd circle
			(at -0.40005 0)
			(size 0 0)
			(layers "F.Cu" "F.Mask" "F.Paste")
			(net "H_CPU1_MEMHOT_IN_LVC1_R1_N")
		)
		(pad "2" smd circle
			(at 0.40005 0)
			(size 0 0)
			(layers "F.Cu" "F.Mask" "F.Paste")
			(net "H_CPU1_MEMHOT_IN_LVC1_N")
		)
	)
	(footprint ""
		(layer "F.Cu")
		(at 317.396622 -59.299348 180)
		(property "Reference" "R1221"
			(at 0 0 180)
			(layer "F.SilkS")
			(hide yes)
			(effects
				(font
					(size 1.27 1.27)
				)
			)
		)
		(property "Value" ""
			(at 0 0 180)
			(layer "F.Fab")
			(effects
				(font
					(size 1.27 1.27)
				)
			)
		)
		(duplicate_pad_numbers_are_jumpers no)
		(fp_line
			(start 0.7874 0.4064)
			(end -0.7874 0.4064)
			(stroke
				(width 0.1524)
				(type default)
			)
			(layer "F.SilkS")
		)
		(fp_line
			(start 0.7874 -0.4064)
			(end 0.7874 0.4064)
			(stroke
				(width 0.1524)
				(type default)
			)
			(layer "F.SilkS")
		)
		(fp_line
			(start -0.7874 0.4064)
			(end -0.7874 -0.4064)
			(stroke
				(width 0.1524)
				(type default)
			)
			(layer "F.SilkS")
		)
		(fp_line
			(start -0.7874 -0.4064)
			(end 0.7874 -0.4064)
			(stroke
				(width 0.1524)
				(type default)
			)
			(layer "F.SilkS")
		)
		(fp_line
			(start 0.67945 0.3048)
			(end 0.120396 0.3048)
			(stroke
				(width 0.1)
				(type default)
			)
			(layer "F.Fab")
		)
		(fp_line
			(start 0.67945 -0.3048)
			(end 0.67945 0.3048)
			(stroke
				(width 0.1)
				(type default)
			)
			(layer "F.Fab")
		)
		(fp_line
			(start 0.12065 -0.2794)
			(end 0.12065 -0.3048)
			(stroke
				(width 0.1)
				(type default)
			)
			(layer "F.Fab")
		)
		(fp_line
			(start 0.12065 -0.3048)
			(end 0.67945 -0.3048)
			(stroke
				(width 0.1)
				(type default)
			)
			(layer "F.Fab")
		)
		(fp_line
			(start 0.120396 0.3048)
			(end 0.120396 0.2794)
			(stroke
				(width 0.1)
				(type default)
			)
			(layer "F.Fab")
		)
		(fp_line
			(start 0.120396 0.2794)
			(end -0.12065 0.2794)
			(stroke
				(width 0.1)
				(type default)
			)
			(layer "F.Fab")
		)
		(fp_line
			(start -0.12065 0.3048)
			(end -0.67945 0.3048)
			(stroke
				(width 0.1)
				(type default)
			)
			(layer "F.Fab")
		)
		(fp_line
			(start -0.12065 0.2794)
			(end -0.12065 0.3048)
			(stroke
				(width 0.1)
				(type default)
			)
			(layer "F.Fab")
		)
		(fp_line
			(start -0.12065 -0.2794)
			(end 0.12065 -0.2794)
			(stroke
				(width 0.1)
				(type default)
			)
			(layer "F.Fab")
		)
		(fp_line
			(start -0.12065 -0.305054)
			(end -0.12065 -0.2794)
			(stroke
				(width 0.1)
				(type default)
			)
			(layer "F.Fab")
		)
		(fp_line
			(start -0.67945 0.3048)
			(end -0.67945 -0.305054)
			(stroke
				(width 0.1)
				(type default)
			)
			(layer "F.Fab")
		)
		(fp_line
			(start -0.67945 -0.305054)
			(end -0.12065 -0.305054)
			(stroke
				(width 0.1)
				(type default)
			)
			(layer "F.Fab")
		)
		(pad "1" smd circle
			(at -0.40005 0 180)
			(size 0 0)
			(layers "F.Cu" "F.Mask" "F.Paste")
			(net "FM_PCH_MCRO_LDO")
		)
		(pad "2" smd circle
			(at 0.40005 0 180)
			(size 0 0)
			(layers "F.Cu" "F.Mask" "F.Paste")
			(net "GND")
		)
	)
)
